# T6G (Grand Teton) — schematic netlist excerpt (pin names and nets, part order shuffled) for the footprints in the layout excerpt that follows; sources: Cadence DE-HDL packaged netlist, KiCad conversion of 04192023_DAF0TMB3IC0_F0TG_MB_C_brd_V02_OCP.brd

C1772  Q_CAP  0.1UF 25V 10% X7R  pkg 0402  page 127 : A = RST_BMC_FROM_SWB_ISO_N ; B = GND

PL59  Q_INDUCTOR4P_14  150NH IND  pkg L_TLM117513Q-151QL_11X7-5XA  page 195
  \1\  = SW_PVDDCR_CPU0_P0_SW3
  \2\  = IND_CPU0_P0_CPL2
  \3\  = IND_CPU0_P0_CPL3
  \4\  = PVDDCR_CPU0_P0

(kicad_pcb
	(version 20260206)
	(generator "pcbnew")
	(generator_version "10.0")
	(general
		(thickness 1.6)
		(legacy_teardrops no)
	)
	(paper "A4")
	(title_block
		(title "04192023_DAF0TMB3IC0_F0TG_MB_C_brd_V02_OCP.brd")
		(comment 1 "Grand Teton / footprints 626-627 of 8354")
	)
	(layers
		(0 "F.Cu" signal "TOP")
		(4 "In1.Cu" signal "GND")
		(6 "In2.Cu" signal "IN1")
		(8 "In3.Cu" signal "GND1")
		(10 "In4.Cu" signal "IN2")
		(12 "In5.Cu" signal "GND2")
		(14 "In6.Cu" signal "IN3")
		(16 "In7.Cu" signal "GND3")
		(18 "In8.Cu" signal "VCC")
		(20 "In9.Cu" signal "VCC1")
		(22 "In10.Cu" signal "GND4")
		(24 "In11.Cu" signal "IN4")
		(26 "In12.Cu" signal "GND5")
		(28 "In13.Cu" signal "IN5")
		(30 "In14.Cu" signal "GND6")
		(32 "In15.Cu" signal "IN6")
		(34 "In16.Cu" signal "GND7")
		(2 "B.Cu" signal "BOTTOM")
		(9 "F.Adhes" user "F.Adhesive")
		(11 "B.Adhes" user "B.Adhesive")
		(13 "F.Paste" user "Package Geometry/Pastemask Top")
		(15 "B.Paste" user "Package Geometry/Pastemask Bottom")
		(5 "F.SilkS" user "Ref Des/Silkscreen Top")
		(7 "B.SilkS" user "Ref Des/Silkscreen Bottom")
		(1 "F.Mask" user "Board Geometry/Soldermask Top")
		(3 "B.Mask" user "Board Geometry/Soldermask Bottom")
		(17 "Dwgs.User" user "User.Drawings")
		(19 "Cmts.User" user "User.Comments")
		(21 "Eco1.User" user "User.Eco1")
		(23 "Eco2.User" user "User.Eco2")
		(25 "Edge.Cuts" user "Board Geometry/Outline")
		(27 "Margin" user)
		(31 "F.CrtYd" user "Package Geometry/Place Bound Top")
		(29 "B.CrtYd" user "Package Geometry/Place Bound Bottom")
		(35 "F.Fab" user "Ref Des/Assembly Top")
		(33 "B.Fab" user "Ref Des/Assembly Bottom")
	)
	(footprint ""
		(layer "F.Cu")
		(at 420.246302 -438.234836 -90)
		(property "Reference" "C1772"
			(at 0 0 270)
			(layer "F.SilkS")
			(hide yes)
			(effects
				(font
					(size 1.27 1.27)
				)
			)
		)
		(property "Value" ""
			(at 0 0 270)
			(layer "F.Fab")
			(effects
				(font
					(size 1.27 1.27)
				)
			)
		)
		(duplicate_pad_numbers_are_jumpers no)
		(fp_line
			(start -0.7874 0.4064)
			(end -0.7874 -0.4064)
			(stroke
				(width 0.1524)
				(type default)
			)
			(layer "F.SilkS")
		)
		(fp_line
			(start 0.7874 0.4064)
			(end -0.7874 0.4064)
			(stroke
				(width 0.1524)
				(type default)
			)
			(layer "F.SilkS")
		)
		(fp_line
			(start -0.7874 -0.4064)
			(end 0.7874 -0.4064)
			(stroke
				(width 0.1524)
				(type default)
			)
			(layer "F.SilkS")
		)
		(fp_line
			(start 0.7874 -0.4064)
			(end 0.7874 0.4064)
			(stroke
				(width 0.1524)
				(type default)
			)
			(layer "F.SilkS")
		)
		(fp_line
			(start -0.67945 0.3048)
			(end -0.67945 -0.305054)
			(stroke
				(width 0.1)
				(type default)
			)
			(layer "F.Fab")
		)
		(fp_line
			(start -0.12065 0.3048)
			(end -0.67945 0.3048)
			(stroke
				(width 0.1)
				(type default)
			)
			(layer "F.Fab")
		)
		(fp_line
			(start 0.120396 0.3048)
			(end 0.120396 0.2794)
			(stroke
				(width 0.1)
				(type default)
			)
			(layer "F.Fab")
		)
		(fp_line
			(start 0.67945 0.3048)
			(end 0.120396 0.3048)
			(stroke
				(width 0.1)
				(type default)
			)
			(layer "F.Fab")
		)
		(fp_line
			(start -0.12065 0.2794)
			(end -0.12065 0.3048)
			(stroke
				(width 0.1)
				(type default)
			)
			(layer "F.Fab")
		)
		(fp_line
			(start 0.120396 0.2794)
			(end -0.12065 0.2794)
			(stroke
				(width 0.1)
				(type default)
			)
			(layer "F.Fab")
		)
		(fp_line
			(start -0.12065 -0.2794)
			(end 0.12065 -0.2794)
			(stroke
				(width 0.1)
				(type default)
			)
			(layer "F.Fab")
		)
		(fp_line
			(start 0.12065 -0.2794)
			(end 0.12065 -0.3048)
			(stroke
				(width 0.1)
				(type default)
			)
			(layer "F.Fab")
		)
		(fp_line
			(start 0.12065 -0.3048)
			(end 0.67945 -0.3048)
			(stroke
				(width 0.1)
				(type default)
			)
			(layer "F.Fab")
		)
		(fp_line
			(start 0.67945 -0.3048)
			(end 0.67945 0.3048)
			(stroke
				(width 0.1)
				(type default)
			)
			(layer "F.Fab")
		)
		(fp_line
			(start -0.67945 -0.305054)
			(end -0.12065 -0.305054)
			(stroke
				(width 0.1)
				(type default)
			)
			(layer "F.Fab")
		)
		(fp_line
			(start -0.12065 -0.305054)
			(end -0.12065 -0.2794)
			(stroke
				(width 0.1)
				(type default)
			)
			(layer "F.Fab")
		)
		(pad "1" smd circle
			(at -0.40005 0 270)
			(size 0 0)
			(layers "F.Cu" "F.Mask" "F.Paste")
			(net "RST_BMC_FROM_SWB_ISO_N")
		)
		(pad "2" smd circle
			(at 0.40005 0 270)
			(size 0 0)
			(layers "F.Cu" "F.Mask" "F.Paste")
			(net "GND")
		)
	)
	(footprint ""
		(layer "F.Cu")
		(at 380.960122 -192.061084 180)
		(property "Reference" "PL59"
			(at -12.840716 3.143758 90)
			(unlocked yes)
			(layer "F.SilkS")
			(effects
				(font
					(size 0.7874 0.5842)
					(thickness 0.1524)
				)
				(justify left)
			)
		)
		(property "Value" ""
			(at 0 0 180)
			(layer "F.Fab")
			(effects
				(font
					(size 1.27 1.27)
				)
			)
		)
		(duplicate_pad_numbers_are_jumpers no)
		(fp_line
			(start 3.750056 5.500116)
			(end 3.750056 -5.500116)
			(stroke
				(width 0.1524)
				(type default)
			)
			(layer "F.SilkS")
		)
		(fp_line
			(start 3.750056 -5.500116)
			(end 2.393442 -5.500116)
			(stroke
				(width 0.1524)
				(type default)
			)
			(layer "F.SilkS")
		)
		(fp_line
			(start 2.393442 5.500116)
			(end 3.750056 5.500116)
			(stroke
				(width 0.1524)
				(type default)
			)
			(layer "F.SilkS")
		)
		(fp_line
			(start -2.393442 5.500116)
			(end -3.750056 5.500116)
			(stroke
				(width 0.1524)
				(type default)
			)
			(layer "F.SilkS")
		)
		(fp_line
			(start -3.750056 5.500116)
			(end -3.750056 -5.500116)
			(stroke
				(width 0.1524)
				(type default)
			)
			(layer "F.SilkS")
		)
		(fp_line
			(start -3.750056 -5.500116)
			(end -2.393442 -5.500116)
			(stroke
				(width 0.1524)
				(type default)
			)
			(layer "F.SilkS")
		)
		(fp_poly
			(pts
				(xy -3.9116 -4.249928) (xy -4.421378 -3.995166) (xy -4.421378 -4.50469)
			)
			(stroke
				(width 0)
				(type default)
			)
			(fill yes)
			(layer "F.SilkS")
		)
		(fp_line
			(start 3.750056 5.500116)
			(end 3.750056 -5.500116)
			(stroke
				(width 0.1)
				(type default)
			)
			(layer "F.Fab")
		)
		(fp_line
			(start 3.750056 -5.500116)
			(end -3.750056 -5.500116)
			(stroke
				(width 0.1)
				(type default)
			)
			(layer "F.Fab")
		)
		(fp_line
			(start -3.750056 5.500116)
			(end 3.750056 5.500116)
			(stroke
				(width 0.1)
				(type default)
			)
			(layer "F.Fab")
		)
		(fp_line
			(start -3.750056 -5.500116)
			(end -3.750056 5.500116)
			(stroke
				(width 0.1)
				(type default)
			)
			(layer "F.Fab")
		)
		(fp_poly
			(pts
				(xy -4.9276 -4.757928) (xy -4.9276 -3.741928) (xy -3.9116 -4.249928)
			)
			(stroke
				(width 0)
				(type default)
			)
			(fill yes)
			(layer "F.Fab")
		)
		(pad "1" smd rect
			(at 0 -4.249928 90)
			(size 2.413 4.5212)
			(layers "F.Cu" "F.Mask" "F.Paste")
			(net "SW_PVDDCR_CPU0_P0_SW3")
		)
		(pad "2" smd rect
			(at 0 -1.175004 90)
			(size 1.3716 4.5212)
			(layers "F.Cu" "F.Mask" "F.Paste")
			(net "IND_CPU0_P0_CPL2")
		)
		(pad "3" smd rect
			(at 0 1.175004 90)
			(size 1.3716 4.5212)
			(layers "F.Cu" "F.Mask" "F.Paste")
			(net "IND_CPU0_P0_CPL3")
		)
		(pad "4" smd rect
			(at 0 4.249928 90)
			(size 2.413 4.5212)
			(layers "F.Cu" "F.Mask" "F.Paste")
			(net "PVDDCR_CPU0_P0")
		)
	)
)
